(kicad_pcb
	(version 20241229)
	(generator "pcbnew")
	(generator_version "9.0")
	(general
		(thickness 1.61)
		(legacy_teardrops no)
	)
	(paper "A3")
	(title_block
		(title "SO-DIMM DDR5 Tester")
		(date "2025-11-26")
		(rev "1.3.0")
		(comment 9 "footprints 566-572 of 627")
	)
	(layers
		(0 "F.Cu" signal)
		(4 "In1.Cu" power)
		(6 "In2.Cu" mixed)
		(8 "In3.Cu" power)
		(10 "In4.Cu" mixed)
		(12 "In5.Cu" power)
		(14 "In6.Cu" mixed)
		(16 "In7.Cu" power)
		(18 "In8.Cu" power)
		(20 "In9.Cu" mixed)
		(22 "In10.Cu" power)
		(2 "B.Cu" signal)
		(9 "F.Adhes" user "F.Adhesive")
		(11 "B.Adhes" user "B.Adhesive")
		(13 "F.Paste" user)
		(15 "B.Paste" user)
		(5 "F.SilkS" user "F.Silkscreen")
		(7 "B.SilkS" user "B.Silkscreen")
		(1 "F.Mask" user)
		(3 "B.Mask" user)
		(17 "Dwgs.User" user "User.Drawings")
		(19 "Cmts.User" user "User.Comments")
		(21 "Eco1.User" user "User.Eco1")
		(23 "Eco2.User" user "User.Eco2")
		(25 "Edge.Cuts" user)
		(27 "Margin" user)
		(31 "F.CrtYd" user "F.Courtyard")
		(29 "B.CrtYd" user "B.Courtyard")
		(35 "F.Fab" user)
		(33 "B.Fab" user)
	)
	(footprint "antmicro-footprints:C_0603_1608Metric"
		(layer "B.Cu")
		(at 136.075001 160.2025 90)
		(descr "Capacitor SMD 0603")
		(tags "capacitor 0603")
		(property "Reference" "C85"
			(at 0 0.9 90)
			(layer "B.SilkS")
			(hide yes)
			(effects
				(font
					(size 0.7 0.7)
					(thickness 0.15)
				)
				(justify right bottom mirror)
			)
		)
		(property "Value" "C_47u_0603"
			(at 0 -1.6 90)
			(layer "B.Fab")
			(effects
				(font
					(size 0.7 0.7)
					(thickness 0.15)
				)
				(justify right bottom mirror)
			)
		)
		(property "Datasheet" "https://www.murata.com/products/productdetail?partno=GRM188R60J476ME15%23"
			(at 0 0 90)
			(layer "F.Fab")
			(hide yes)
			(effects
				(font
					(size 1.27 1.27)
					(thickness 0.15)
				)
			)
		)
		(property "Author" "Antmicro"
			(at 296.277501 24.127499 0)
			(layer "B.Fab")
			(hide yes)
			(effects
				(font
					(size 1 1)
					(thickness 0.15)
				)
				(justify mirror)
			)
		)
		(property "Dielectric" ""
			(at 296.277501 24.127499 0)
			(layer "B.Fab")
			(hide yes)
			(effects
				(font
					(size 1 1)
					(thickness 0.15)
				)
				(justify mirror)
			)
		)
		(property "License" "Apache-2.0"
			(at 296.277501 24.127499 0)
			(layer "B.Fab")
			(hide yes)
			(effects
				(font
					(size 1 1)
					(thickness 0.15)
				)
				(justify mirror)
			)
		)
		(property "MPN" "GRM188R60J476ME15D"
			(at 296.277501 24.127499 0)
			(layer "B.Fab")
			(hide yes)
			(effects
				(font
					(size 1 1)
					(thickness 0.15)
				)
				(justify mirror)
			)
		)
		(property "Manufacturer" "Murata"
			(at 296.277501 24.127499 0)
			(layer "B.Fab")
			(hide yes)
			(effects
				(font
					(size 1 1)
					(thickness 0.15)
				)
				(justify mirror)
			)
		)
		(property "Val" "47u"
			(at 296.277501 24.127499 0)
			(layer "B.Fab")
			(hide yes)
			(effects
				(font
					(size 1 1)
					(thickness 0.15)
				)
				(justify mirror)
			)
		)
		(property "Voltage" ""
			(at 296.277501 24.127499 0)
			(layer "B.Fab")
			(hide yes)
			(effects
				(font
					(size 1 1)
					(thickness 0.15)
				)
				(justify mirror)
			)
		)
		(sheetname "/FPGA power/")
		(sheetfile "fpga-power.kicad_sch")
		(attr smd)
		(fp_line
			(start -0.3 -0.3)
			(end 0.3 -0.3)
			(stroke
				(width 0.15)
				(type solid)
			)
			(layer "B.SilkS")
		)
		(fp_line
			(start -0.3 0.3)
			(end 0.3 0.3)
			(stroke
				(width 0.15)
				(type solid)
			)
			(layer "B.SilkS")
		)
		(fp_rect
			(start -1.24 0.7)
			(end 1.24 -0.7)
			(stroke
				(width 0.05)
				(type solid)
			)
			(fill no)
			(layer "B.CrtYd")
		)
		(fp_rect
			(start -0.8 0.4)
			(end 0.8 -0.4)
			(stroke
				(width 0.15)
				(type solid)
			)
			(fill no)
			(layer "B.Fab")
		)
		(pad "1" smd roundrect
			(at -0.7 0 90)
			(size 0.6 0.8)
			(layers "B.Cu" "B.Mask" "B.Paste")
			(roundrect_rratio 0.2)
			(net 206 "+1V1")
			(pintype "passive")
		)
		(pad "2" smd roundrect
			(at 0.7 0 90)
			(size 0.6 0.8)
			(layers "B.Cu" "B.Mask" "B.Paste")
			(roundrect_rratio 0.2)
			(net 1 "GND")
			(pintype "passive")
		)
	)
	(footprint "antmicro-footprints:R_0402_1005Metric"
		(layer "B.Cu")
		(at 123.15 183.099999)
		(descr "Resistor SMD 0402")
		(tags "resistor SMD 0402")
		(property "Reference" "R3"
			(at -1.122484 0.772697 180)
			(layer "B.SilkS")
			(hide yes)
			(effects
				(font
					(size 0.7 0.7)
					(thickness 0.15)
				)
				(justify left bottom mirror)
			)
		)
		(property "Value" "R_2k2_0402"
			(at -1.011843 -1.772047 180)
			(layer "B.Fab")
			(effects
				(font
					(size 0.7 0.7)
					(thickness 0.15)
				)
				(justify left bottom mirror)
			)
		)
		(property "Datasheet" "https://www.bourns.com/docs/product-datasheets/cr.pdf"
			(at 0 0 0)
			(layer "F.Fab")
			(hide yes)
			(effects
				(font
					(size 1.27 1.27)
					(thickness 0.15)
				)
			)
		)
		(property "Author" "Antmicro"
			(at 0 0 0)
			(layer "B.Fab")
			(hide yes)
			(effects
				(font
					(size 1 1)
					(thickness 0.15)
				)
				(justify mirror)
			)
		)
		(property "License" "Apache-2.0"
			(at 0 0 0)
			(layer "B.Fab")
			(hide yes)
			(effects
				(font
					(size 1 1)
					(thickness 0.15)
				)
				(justify mirror)
			)
		)
		(property "MPN" "CR0402-FX-2201GLF"
			(at 0 0 0)
			(layer "B.Fab")
			(hide yes)
			(effects
				(font
					(size 1 1)
					(thickness 0.15)
				)
				(justify mirror)
			)
		)
		(property "Manufacturer" "Bourns"
			(at 0 0 0)
			(layer "B.Fab")
			(hide yes)
			(effects
				(font
					(size 1 1)
					(thickness 0.15)
				)
				(justify mirror)
			)
		)
		(property "Tolerance" "1%"
			(at 0 0 0)
			(layer "B.Fab")
			(hide yes)
			(effects
				(font
					(size 1 1)
					(thickness 0.15)
				)
				(justify mirror)
			)
		)
		(property "Val" "2k2"
			(at 0 0 0)
			(layer "B.Fab")
			(hide yes)
			(effects
				(font
					(size 1 1)
					(thickness 0.15)
				)
				(justify mirror)
			)
		)
		(sheetname "/HyperRAM + QSPI Flash/")
		(sheetfile "hyperram-flash.kicad_sch")
		(attr smd)
		(fp_rect
			(start -0.93 0.47)
			(end 0.93 -0.47)
			(stroke
				(width 0.05)
				(type solid)
			)
			(fill no)
			(layer "B.CrtYd")
		)
		(fp_rect
			(start -0.5 0.25)
			(end 0.5 -0.25)
			(stroke
				(width 0.15)
				(type solid)
			)
			(fill no)
			(layer "B.Fab")
		)
		(pad "1" smd roundrect
			(at -0.485 0)
			(size 0.59 0.64)
			(layers "B.Cu" "B.Mask" "B.Paste")
			(roundrect_rratio 0.25)
			(net 200 "+3V3")
			(pintype "passive")
		)
		(pad "2" smd roundrect
			(at 0.485 0)
			(size 0.59 0.64)
			(layers "B.Cu" "B.Mask" "B.Paste")
			(roundrect_rratio 0.25)
			(net 625 "/FPGA Config/FLASH.~{CS}")
			(pintype "passive")
		)
	)
	(footprint "antmicro-footprints:R_0402_1005Metric"
		(layer "B.Cu")
		(at 180.8 192 180)
		(descr "Resistor SMD 0402")
		(tags "resistor SMD 0402")
		(property "Reference" "R179"
			(at 1.25 -0.4 0)
			(layer "B.SilkS")
			(effects
				(font
					(size 0.7 0.7)
					(thickness 0.15)
				)
				(justify left bottom mirror)
			)
		)
		(property "Value" "R_0R_0402"
			(at -1.011843 -1.772047 0)
			(layer "B.Fab")
			(effects
				(font
					(size 0.7 0.7)
					(thickness 0.15)
				)
				(justify left bottom mirror)
			)
		)
		(property "Datasheet" "https://industrial.panasonic.com/cdbs/www-data/pdf/RDA0000/AOA0000C301.pdf"
			(at 0 0 180)
			(layer "F.Fab")
			(hide yes)
			(effects
				(font
					(size 1.27 1.27)
					(thickness 0.15)
				)
			)
		)
		(property "Author" "Antmicro"
			(at 361.6 384 0)
			(layer "B.Fab")
			(hide yes)
			(effects
				(font
					(size 1 1)
					(thickness 0.15)
				)
				(justify mirror)
			)
		)
		(property "Current" "1A"
			(at 361.6 384 0)
			(layer "B.Fab")
			(hide yes)
			(effects
				(font
					(size 1 1)
					(thickness 0.15)
				)
				(justify mirror)
			)
		)
		(property "License" "Apache-2.0"
			(at 361.6 384 0)
			(layer "B.Fab")
			(hide yes)
			(effects
				(font
					(size 1 1)
					(thickness 0.15)
				)
				(justify mirror)
			)
		)
		(property "MPN" "ERJ2GE0R00X"
			(at 361.6 384 0)
			(layer "B.Fab")
			(hide yes)
			(effects
				(font
					(size 1 1)
					(thickness 0.15)
				)
				(justify mirror)
			)
		)
		(property "Manufacturer" "Panasonic"
			(at 361.6 384 0)
			(layer "B.Fab")
			(hide yes)
			(effects
				(font
					(size 1 1)
					(thickness 0.15)
				)
				(justify mirror)
			)
		)
		(property "Tolerance" ""
			(at 361.6 384 0)
			(layer "B.Fab")
			(hide yes)
			(effects
				(font
					(size 1 1)
					(thickness 0.15)
				)
				(justify mirror)
			)
		)
		(property "Val" "0R"
			(at 361.6 384 0)
			(layer "B.Fab")
			(hide yes)
			(effects
				(font
					(size 1 1)
					(thickness 0.15)
				)
				(justify mirror)
			)
		)
		(sheetname "/I^{2}C/")
		(sheetfile "i2c.kicad_sch")
		(attr exclude_from_pos_files exclude_from_bom dnp)
		(fp_rect
			(start -0.93 0.47)
			(end 0.93 -0.47)
			(stroke
				(width 0.05)
				(type solid)
			)
			(fill no)
			(layer "B.CrtYd")
		)
		(fp_rect
			(start -0.5 0.25)
			(end 0.5 -0.25)
			(stroke
				(width 0.15)
				(type solid)
			)
			(fill no)
			(layer "B.Fab")
		)
		(pad "1" smd roundrect
			(at -0.485 0 180)
			(size 0.59 0.64)
			(layers "B.Cu" "B.Mask" "B.Paste")
			(roundrect_rratio 0.25)
			(net 691 "/I^{2}C/PWR.SCL")
			(pintype "passive")
		)
		(pad "2" smd roundrect
			(at 0.485 0 180)
			(size 0.59 0.64)
			(layers "B.Cu" "B.Mask" "B.Paste")
			(roundrect_rratio 0.25)
			(net 671 "/Debug FTDI/FTDI.SCL")
			(pintype "passive")
		)
	)
	(footprint "antmicro-footprints:C_0402_1005Metric"
		(layer "B.Cu")
		(at 202.9 167.9 -90)
		(descr "Capacitor SMD 0402")
		(tags "capacitor SMD 0402")
		(property "Reference" "C174"
			(at 0 0.699 90)
			(layer "B.SilkS")
			(hide yes)
			(effects
				(font
					(size 0.7 0.7)
					(thickness 0.15)
				)
				(justify left bottom mirror)
			)
		)
		(property "Value" "C_1u_0402"
			(at -1.022927 -2.155213 90)
			(layer "B.Fab")
			(effects
				(font
					(size 0.7 0.7)
					(thickness 0.15)
				)
				(justify left bottom mirror)
			)
		)
		(property "Datasheet" "https://product.tdk.com/en/search/capacitor/ceramic/mlcc/info?part_no=C1005X6S1A105K050BC"
			(at 0 0 270)
			(layer "F.Fab")
			(hide yes)
			(effects
				(font
					(size 1.27 1.27)
					(thickness 0.15)
				)
			)
		)
		(property "Author" "Antmicro"
			(at 35 370.8 0)
			(layer "B.Fab")
			(hide yes)
			(effects
				(font
					(size 1 1)
					(thickness 0.15)
				)
				(justify mirror)
			)
		)
		(property "Dielectric" ""
			(at 35 370.8 0)
			(layer "B.Fab")
			(hide yes)
			(effects
				(font
					(size 1 1)
					(thickness 0.15)
				)
				(justify mirror)
			)
		)
		(property "License" "Apache-2.0"
			(at 35 370.8 0)
			(layer "B.Fab")
			(hide yes)
			(effects
				(font
					(size 1 1)
					(thickness 0.15)
				)
				(justify mirror)
			)
		)
		(property "MPN" "C1005X6S1A105K050BC"
			(at 35 370.8 0)
			(layer "B.Fab")
			(hide yes)
			(effects
				(font
					(size 1 1)
					(thickness 0.15)
				)
				(justify mirror)
			)
		)
		(property "Manufacturer" "TDK"
			(at 35 370.8 0)
			(layer "B.Fab")
			(hide yes)
			(effects
				(font
					(size 1 1)
					(thickness 0.15)
				)
				(justify mirror)
			)
		)
		(property "Val" "1u"
			(at 35 370.8 0)
			(layer "B.Fab")
			(hide yes)
			(effects
				(font
					(size 1 1)
					(thickness 0.15)
				)
				(justify mirror)
			)
		)
		(property "Voltage" ""
			(at 35 370.8 0)
			(layer "B.Fab")
			(hide yes)
			(effects
				(font
					(size 1 1)
					(thickness 0.15)
				)
				(justify mirror)
			)
		)
		(sheetname "/Supply/")
		(sheetfile "supply.kicad_sch")
		(attr smd)
		(fp_rect
			(start -0.9659 0.481258)
			(end 0.9649 -0.458742)
			(stroke
				(width 0.05)
				(type solid)
			)
			(fill no)
			(layer "B.CrtYd")
		)
		(fp_line
			(start -0.499 0.25)
			(end 0.499 0.25)
			(stroke
				(width 0.15)
				(type solid)
			)
			(layer "B.Fab")
		)
		(fp_line
			(start 0.499 0.25)
			(end 0.499 -0.248)
			(stroke
				(width 0.15)
				(type solid)
			)
			(layer "B.Fab")
		)
		(fp_line
			(start -0.499 -0.248)
			(end -0.499 0.25)
			(stroke
				(width 0.15)
				(type solid)
			)
			(layer "B.Fab")
		)
		(fp_line
			(start 0.499 -0.248)
			(end -0.499 -0.248)
			(stroke
				(width 0.15)
				(type solid)
			)
			(layer "B.Fab")
		)
		(pad "1" smd roundrect
			(at -0.484 0 270)
			(size 0.59 0.64)
			(layers "B.Cu" "B.Mask" "B.Paste")
			(roundrect_rratio 0.25)
			(net 1 "GND")
			(pintype "passive")
		)
		(pad "2" smd roundrect
			(at 0.484 0 270)
			(size 0.59 0.64)
			(layers "B.Cu" "B.Mask" "B.Paste")
			(roundrect_rratio 0.25)
			(net 40 "/Supply/QDCDC2_VCC")
			(pintype "passive")
		)
	)
	(footprint "antmicro-footprints:TP_SMD_1mm"
		(layer "B.Cu")
		(at 105.937096 187.9 90)
		(property "Reference" "TP53"
			(at -3.68 -0.272904 90)
			(layer "B.SilkS")
			(effects
				(font
					(size 0.7 0.7)
					(thickness 0.15)
				)
				(justify right top mirror)
			)
		)
		(property "Value" "TP_1mm_SMD"
			(at 0 -1.4 90)
			(layer "B.Fab")
			(effects
				(font
					(size 0.7 0.7)
					(thickness 0.15)
				)
				(justify right top mirror)
			)
		)
		(property "MPN" ""
			(at 0 0 270)
			(unlocked yes)
			(layer "B.Fab")
			(hide yes)
			(effects
				(font
					(size 1 1)
					(thickness 0.15)
				)
				(justify mirror)
			)
		)
		(property "Manufacturer" ""
			(at 0 0 270)
			(unlocked yes)
			(layer "B.Fab")
			(hide yes)
			(effects
				(font
					(size 1 1)
					(thickness 0.15)
				)
				(justify mirror)
			)
		)
		(property "Author" "Antmicro"
			(at 0 0 270)
			(unlocked yes)
			(layer "B.Fab")
			(hide yes)
			(effects
				(font
					(size 1 1)
					(thickness 0.15)
				)
				(justify mirror)
			)
		)
		(property "License" "Apache-2.0"
			(at 0 0 270)
			(unlocked yes)
			(layer "B.Fab")
			(hide yes)
			(effects
				(font
					(size 1 1)
					(thickness 0.15)
				)
				(justify mirror)
			)
		)
		(sheetname "/Debug FTDI/")
		(sheetfile "debug-ftdi.kicad_sch")
		(attr exclude_from_pos_files)
		(fp_circle
			(center 0 0)
			(end 0.6 0)
			(stroke
				(width 0.05)
				(type default)
			)
			(fill no)
			(layer "B.CrtYd")
		)
		(fp_text user "Author: Antmicro"
			(at -0.5 -4 90)
			(layer "B.Fab")
			(effects
				(font
					(size 0.7 0.7)
					(thickness 0.15)
				)
				(justify right top mirror)
			)
		)
		(fp_text user "License: Apache-2.0"
			(at -0.5 -5.2 90)
			(layer "B.Fab")
			(effects
				(font
					(size 0.7 0.7)
					(thickness 0.15)
				)
				(justify right top mirror)
			)
		)
		(fp_text user "${REFERENCE}"
			(at -0.5 -2.8 90)
			(layer "B.Fab")
			(effects
				(font
					(size 0.7 0.7)
					(thickness 0.15)
				)
				(justify right top mirror)
			)
		)
		(pad "1" smd circle
			(at 0 0 90)
			(size 1 1)
			(layers "B.Cu" "B.Mask")
			(net 671 "/Debug FTDI/FTDI.SCL")
			(pinfunction "1")
			(pintype "passive")
		)
	)
	(footprint "antmicro-footprints:C_0402_1005Metric"
		(layer "B.Cu")
		(at 132.525501 204.850501 90)
		(descr "Capacitor SMD 0402")
		(tags "capacitor SMD 0402")
		(property "Reference" "C232"
			(at 0 0.699 270)
			(layer "B.SilkS")
			(hide yes)
			(effects
				(font
					(size 0.7 0.7)
					(thickness 0.15)
				)
				(justify left bottom mirror)
			)
		)
		(property "Value" "C_100n_0402"
			(at -1.022927 -2.155213 270)
			(layer "B.Fab")
			(effects
				(font
					(size 0.7 0.7)
					(thickness 0.15)
				)
				(justify left bottom mirror)
			)
		)
		(property "Datasheet" "https://www.murata.com/products/productdetail?partno=GRM155R61H104KE14%23"
			(at 0 0 90)
			(layer "F.Fab")
			(hide yes)
			(effects
				(font
					(size 1.27 1.27)
					(thickness 0.15)
				)
			)
		)
		(property "Author" "Antmicro"
			(at 337.376002 72.325 0)
			(layer "B.Fab")
			(hide yes)
			(effects
				(font
					(size 1 1)
					(thickness 0.15)
				)
				(justify mirror)
			)
		)
		(property "Dielectric" "X5R"
			(at 337.376002 72.325 0)
			(layer "B.Fab")
			(hide yes)
			(effects
				(font
					(size 1 1)
					(thickness 0.15)
				)
				(justify mirror)
			)
		)
		(property "License" "Apache-2.0"
			(at 337.376002 72.325 0)
			(layer "B.Fab")
			(hide yes)
			(effects
				(font
					(size 1 1)
					(thickness 0.15)
				)
				(justify mirror)
			)
		)
		(property "MPN" "GRM155R61H104KE14D"
			(at 337.376002 72.325 0)
			(layer "B.Fab")
			(hide yes)
			(effects
				(font
					(size 1 1)
					(thickness 0.15)
				)
				(justify mirror)
			)
		)
		(property "Manufacturer" "Murata"
			(at 337.376002 72.325 0)
			(layer "B.Fab")
			(hide yes)
			(effects
				(font
					(size 1 1)
					(thickness 0.15)
				)
				(justify mirror)
			)
		)
		(property "Val" "100n"
			(at 337.376002 72.325 0)
			(layer "B.Fab")
			(hide yes)
			(effects
				(font
					(size 1 1)
					(thickness 0.15)
				)
				(justify mirror)
			)
		)
		(property "Voltage" "50V"
			(at 337.376002 72.325 0)
			(layer "B.Fab")
			(hide yes)
			(effects
				(font
					(size 1 1)
					(thickness 0.15)
				)
				(justify mirror)
			)
		)
		(sheetname "/FPGA MGT Interface/")
		(sheetfile "fpga-mgt.kicad_sch")
		(attr smd)
		(fp_rect
			(start -0.9659 0.481258)
			(end 0.9649 -0.458742)
			(stroke
				(width 0.05)
				(type solid)
			)
			(fill no)
			(layer "B.CrtYd")
		)
		(fp_line
			(start 0.499 -0.248)
			(end -0.499 -0.248)
			(stroke
				(width 0.15)
				(type solid)
			)
			(layer "B.Fab")
		)
		(fp_line
			(start -0.499 -0.248)
			(end -0.499 0.25)
			(stroke
				(width 0.15)
				(type solid)
			)
			(layer "B.Fab")
		)
		(fp_line
			(start 0.499 0.25)
			(end 0.499 -0.248)
			(stroke
				(width 0.15)
				(type solid)
			)
			(layer "B.Fab")
		)
		(fp_line
			(start -0.499 0.25)
			(end 0.499 0.25)
			(stroke
				(width 0.15)
				(type solid)
			)
			(layer "B.Fab")
		)
		(pad "1" smd roundrect
			(at -0.484 0 90)
			(size 0.59 0.64)
			(layers "B.Cu" "B.Mask" "B.Paste")
			(roundrect_rratio 0.25)
			(net 28 "/FPGA MGT Interface/PCIE.TXD0_N")
			(pintype "passive")
		)
		(pad "2" smd roundrect
			(at 0.484 0 90)
			(size 0.59 0.64)
			(layers "B.Cu" "B.Mask" "B.Paste")
			(roundrect_rratio 0.25)
			(net 29 "/FPGA MGT Interface/GTX_TX3_N")
			(pintype "passive")
		)
	)
	(footprint "antmicro-footprints:TP_SMD_1mm"
		(layer "B.Cu")
		(at 172.3 181.9 180)
		(property "Reference" "TP68"
			(at 0.9 -0.3 0)
			(layer "B.SilkS")
			(effects
				(font
					(size 0.7 0.7)
					(thickness 0.15)
				)
				(justify left bottom mirror)
			)
		)
		(property "Value" "TP_1mm_SMD"
			(at 0 -1.4 0)
			(layer "B.Fab")
			(effects
				(font
					(size 0.7 0.7)
					(thickness 0.15)
				)
				(justify left bottom mirror)
			)
		)
		(property "MPN" ""
			(at 0 0 0)
			(unlocked yes)
			(layer "B.Fab")
			(hide yes)
			(effects
				(font
					(size 1 1)
					(thickness 0.15)
				)
				(justify mirror)
			)
		)
		(property "Manufacturer" ""
			(at 0 0 0)
			(unlocked yes)
			(layer "B.Fab")
			(hide yes)
			(effects
				(font
					(size 1 1)
					(thickness 0.15)
				)
				(justify mirror)
			)
		)
		(property "Author" "Antmicro"
			(at 0 0 0)
			(unlocked yes)
			(layer "B.Fab")
			(hide yes)
			(effects
				(font
					(size 1 1)
					(thickness 0.15)
				)
				(justify mirror)
			)
		)
		(property "License" "Apache-2.0"
			(at 0 0 0)
			(unlocked yes)
			(layer "B.Fab")
			(hide yes)
			(effects
				(font
					(size 1 1)
					(thickness 0.15)
				)
				(justify mirror)
			)
		)
		(sheetname "/I^{2}C/")
		(sheetfile "i2c.kicad_sch")
		(attr exclude_from_pos_files)
		(fp_circle
			(center 0 0)
			(end 0.6 0)
			(stroke
				(width 0.05)
				(type default)
			)
			(fill no)
			(layer "B.CrtYd")
		)
		(fp_text user "License: Apache-2.0"
			(at -0.5 -5.2 0)
			(layer "B.Fab")
			(effects
				(font
					(size 0.7 0.7)
					(thickness 0.15)
				)
				(justify left bottom mirror)
			)
		)
		(fp_text user "Author: Antmicro"
			(at -0.5 -4 0)
			(layer "B.Fab")
			(effects
				(font
					(size 0.7 0.7)
					(thickness 0.15)
				)
				(justify left bottom mirror)
			)
		)
		(fp_text user "${REFERENCE}"
			(at -0.5 -2.8 0)
			(layer "B.Fab")
			(effects
				(font
					(size 0.7 0.7)
					(thickness 0.15)
				)
				(justify left bottom mirror)
			)
		)
		(pad "1" smd circle
			(at 0 0 180)
			(size 1 1)
			(layers "B.Cu" "B.Mask")
			(net 1 "GND")
			(pinfunction "1")
			(pintype "passive")
		)
	)
)
